(kicad_pcb
	(version 20260206)
	(generator "pcbnew")
	(generator_version "10.0")
	(general
		(thickness 1.6)
		(legacy_teardrops no)
	)
	(paper "A4")
	(title_block
		(title "baseboard — 13948-1b.1110WZS1818.brd")
		(comment 1 "Honey Badger (Wiwynn) / footprints 1721-1727 of 2523")
	)
	(layers
		(0 "F.Cu" signal "TOP")
		(4 "In1.Cu" signal "L2GND")
		(6 "In2.Cu" signal "L3")
		(8 "In3.Cu" signal "L4VCC")
		(10 "In4.Cu" signal "L5VCC")
		(12 "In5.Cu" signal "L6")
		(14 "In6.Cu" signal "L7GND")
		(2 "B.Cu" signal "BOTTOM")
		(9 "F.Adhes" user "F.Adhesive")
		(11 "B.Adhes" user "B.Adhesive")
		(13 "F.Paste" user "Package Geometry/Pastemask Top")
		(15 "B.Paste" user "Package Geometry/Pastemask Bottom")
		(5 "F.SilkS" user "Ref Des/Silkscreen Top")
		(7 "B.SilkS" user "Ref Des/Silkscreen Bottom")
		(1 "F.Mask" user "Board Geometry/Soldermask Top")
		(3 "B.Mask" user "Board Geometry/Soldermask Bottom")
		(17 "Dwgs.User" user "User.Drawings")
		(19 "Cmts.User" user "User.Comments")
		(21 "Eco1.User" user "User.Eco1")
		(23 "Eco2.User" user "User.Eco2")
		(25 "Edge.Cuts" user "Board Geometry/Outline")
		(27 "Margin" user)
		(31 "F.CrtYd" user "Package Geometry/Place Bound Top")
		(29 "B.CrtYd" user "Package Geometry/Place Bound Bottom")
		(35 "F.Fab" user "Ref Des/Assembly Top")
		(33 "B.Fab" user "Ref Des/Assembly Bottom")
	)
	(footprint ""
		(layer "F.Cu")
		(at 284.090872 -68.017136 -90)
		(property "Reference" "U34"
			(at 0 0 270)
			(layer "F.SilkS")
			(hide yes)
			(effects
				(font
					(size 1.27 1.27)
				)
			)
		)
		(property "Value" "ADM1178-2ARMZ-R7-GP"
			(at 0 -11.1252 270)
			(unlocked yes)
			(layer "F.Fab")
			(hide yes)
			(effects
				(font
					(size 1.016 1.016)
					(thickness 0.1524)
				)
			)
		)
		(property "Device Type" "MSOP10H44"
			(at 0 -12.6492 270)
			(unlocked yes)
			(layer "F.Fab")
			(hide yes)
			(effects
				(font
					(size 1.016 1.016)
					(thickness 0.1524)
				)
			)
		)
		(duplicate_pad_numbers_are_jumpers no)
		(fp_line
			(start -2.0066 1.016)
			(end -2.0066 -1.016)
			(stroke
				(width 0.1524)
				(type default)
			)
			(layer "F.SilkS")
		)
		(fp_line
			(start -1.8288 1.016)
			(end -1.8288 3.048)
			(stroke
				(width 0.508)
				(type default)
			)
			(layer "F.SilkS")
		)
		(fp_line
			(start 1.143 1.016)
			(end -2.0066 1.016)
			(stroke
				(width 0.1524)
				(type default)
			)
			(layer "F.SilkS")
		)
		(fp_line
			(start -1.5748 0)
			(end -1.9558 0.381)
			(stroke
				(width 0.1524)
				(type default)
			)
			(layer "F.SilkS")
		)
		(fp_line
			(start -1.5748 0)
			(end -1.9558 -0.381)
			(stroke
				(width 0.1524)
				(type default)
			)
			(layer "F.SilkS")
		)
		(fp_line
			(start -2.0066 -1.016)
			(end 1.143 -1.016)
			(stroke
				(width 0.1524)
				(type default)
			)
			(layer "F.SilkS")
		)
		(fp_line
			(start 1.143 -1.016)
			(end 1.143 1.016)
			(stroke
				(width 0.1524)
				(type default)
			)
			(layer "F.SilkS")
		)
		(fp_poly
			(pts
				(xy -2.0828 3.3401) (xy 2.0828 3.3401) (xy 2.0828 -3.3401) (xy -2.0828 -3.3401)
			)
			(stroke
				(width 0)
				(type default)
			)
			(fill no)
			(layer "F.CrtYd")
		)
		(fp_poly
			(pts
				(xy -2.0828 3.3401) (xy 2.0828 3.3401) (xy 2.0828 -3.3401) (xy -2.0828 -3.3401)
			)
			(stroke
				(width 0)
				(type default)
			)
			(fill no)
			(layer "F.Fab")
		)
		(pad "1" smd rect
			(at -0.99949 2.0701 270)
			(size 0.3048 1.524)
			(layers "F.Cu" "F.Mask" "F.Paste")
			(net "P12V_PCIE")
		)
		(pad "2" smd rect
			(at -0.50038 2.0701 270)
			(size 0.3048 1.524)
			(layers "F.Cu" "F.Mask" "F.Paste")
			(net "VSENSE_HSC_MSB")
		)
		(pad "3" smd rect
			(at 0 2.0701 270)
			(size 0.3048 1.524)
			(layers "F.Cu" "F.Mask" "F.Paste")
			(net "PRSNT_EN_HPIC")
		)
		(pad "4" smd rect
			(at 0.50038 2.0701 270)
			(size 0.3048 1.524)
			(layers "F.Cu" "F.Mask" "F.Paste")
			(net "GND")
		)
		(pad "5" smd rect
			(at 0.99949 2.0701 270)
			(size 0.3048 1.524)
			(layers "F.Cu" "F.Mask" "F.Paste")
			(net "VR_HSC_TIMER_MSB")
		)
		(pad "6" smd rect
			(at 0.99949 -2.0701 270)
			(size 0.3048 1.524)
			(layers "F.Cu" "F.Mask" "F.Paste")
			(net "HSW_SCL1")
		)
		(pad "7" smd rect
			(at 0.50038 -2.0701 270)
			(size 0.3048 1.524)
			(layers "F.Cu" "F.Mask" "F.Paste")
			(net "HSW_SDA1")
		)
		(pad "8" smd rect
			(at 0 -2.0701 270)
			(size 0.3048 1.524)
			(layers "F.Cu" "F.Mask" "F.Paste")
			(net "HS_ADR")
		)
		(pad "9" smd rect
			(at -0.50038 -2.0701 270)
			(size 0.3048 1.524)
			(layers "F.Cu" "F.Mask" "F.Paste")
			(net "VR_HSC_GATE_MSB")
		)
		(pad "10" smd rect
			(at -0.99949 -2.0701 270)
			(size 0.3048 1.524)
			(layers "F.Cu" "F.Mask" "F.Paste")
			(net "HSC_MSB_ALERT_N")
		)
	)
	(footprint ""
		(layer "F.Cu")
		(at 276.352 -115.824)
		(property "Reference" "PR176"
			(at 0 0 0)
			(layer "F.SilkS")
			(hide yes)
			(effects
				(font
					(size 1.27 1.27)
				)
			)
		)
		(property "Value" "0R2J-2-GP"
			(at 0.064008 -3.993896 0)
			(unlocked yes)
			(layer "F.Fab")
			(hide yes)
			(effects
				(font
					(size 1.016 1.016)
					(thickness 0.1524)
				)
			)
		)
		(property "Device Type" "R402H16"
			(at 0.064008 -5.517896 0)
			(unlocked yes)
			(layer "F.Fab")
			(hide yes)
			(effects
				(font
					(size 1.016 1.016)
					(thickness 0.1524)
				)
			)
		)
		(duplicate_pad_numbers_are_jumpers no)
		(fp_line
			(start -0.508 -0.9398)
			(end -0.508 0.9398)
			(stroke
				(width 0.1524)
				(type default)
			)
			(layer "F.SilkS")
		)
		(fp_line
			(start 0.508 -0.9398)
			(end -0.508 -0.9398)
			(stroke
				(width 0.1524)
				(type default)
			)
			(layer "F.SilkS")
		)
		(fp_rect
			(start -0.508 0.9398)
			(end 0.508 -0.9398)
			(stroke
				(width 0)
				(type default)
			)
			(fill no)
			(layer "F.CrtYd")
		)
		(fp_rect
			(start -0.508 0.9398)
			(end 0.508 -0.9398)
			(stroke
				(width 0)
				(type default)
			)
			(fill no)
			(layer "F.Fab")
		)
		(pad "1" smd custom
			(at 0 -0.4445)
			(size 0.1397 0.1397)
			(layers "F.Cu" "F.Mask" "F.Paste")
			(net "P3V3_PG")
			(options
				(clearance outline)
				(anchor circle)
			)
			(primitives
				(gr_poly
					(pts
						(arc
							(start -0.1778 -0.2794)
							(mid -0.249642 -0.249642)
							(end -0.2794 -0.1778)
						)
						(arc
							(start -0.2794 0.1778)
							(mid -0.249642 0.249642)
							(end -0.1778 0.2794)
						)
						(arc
							(start 0.1778 0.2794)
							(mid 0.249642 0.249642)
							(end 0.2794 0.1778)
						)
						(arc
							(start 0.2794 -0.1778)
							(mid 0.249642 -0.249642)
							(end 0.1778 -0.2794)
						)
					)
					(width 0)
					(fill yes)
				)
			)
		)
		(pad "2" smd custom
			(at 0 0.4445)
			(size 0.1397 0.1397)
			(layers "F.Cu" "F.Mask" "F.Paste")
			(net "P1V8_C_EN_B")
			(options
				(clearance outline)
				(anchor circle)
			)
			(primitives
				(gr_poly
					(pts
						(arc
							(start -0.1778 -0.2794)
							(mid -0.249642 -0.249642)
							(end -0.2794 -0.1778)
						)
						(arc
							(start -0.2794 0.1778)
							(mid -0.249642 0.249642)
							(end -0.1778 0.2794)
						)
						(arc
							(start 0.1778 0.2794)
							(mid 0.249642 0.249642)
							(end 0.2794 0.1778)
						)
						(arc
							(start 0.2794 -0.1778)
							(mid 0.249642 -0.249642)
							(end 0.1778 -0.2794)
						)
					)
					(width 0)
					(fill yes)
				)
			)
		)
	)
	(footprint ""
		(layer "F.Cu")
		(at 189.865 -20.955 90)
		(property "Reference" "R380"
			(at 0 0 90)
			(layer "F.SilkS")
			(hide yes)
			(effects
				(font
					(size 1.27 1.27)
				)
			)
		)
		(property "Value" "0R2J-2-GP"
			(at 0.064008 -3.993896 90)
			(unlocked yes)
			(layer "F.Fab")
			(hide yes)
			(effects
				(font
					(size 1.016 1.016)
					(thickness 0.1524)
				)
			)
		)
		(property "Device Type" "R402H16"
			(at 0.064008 -5.517896 90)
			(unlocked yes)
			(layer "F.Fab")
			(hide yes)
			(effects
				(font
					(size 1.016 1.016)
					(thickness 0.1524)
				)
			)
		)
		(duplicate_pad_numbers_are_jumpers no)
		(fp_line
			(start 0.508 -0.9398)
			(end -0.508 -0.9398)
			(stroke
				(width 0.1524)
				(type default)
			)
			(layer "F.SilkS")
		)
		(fp_line
			(start -0.508 -0.9398)
			(end -0.508 0.9398)
			(stroke
				(width 0.1524)
				(type default)
			)
			(layer "F.SilkS")
		)
		(fp_rect
			(start -0.508 0.9398)
			(end 0.508 -0.9398)
			(stroke
				(width 0)
				(type default)
			)
			(fill no)
			(layer "F.CrtYd")
		)
		(fp_rect
			(start -0.508 0.9398)
			(end 0.508 -0.9398)
			(stroke
				(width 0)
				(type default)
			)
			(fill no)
			(layer "F.Fab")
		)
		(pad "1" smd custom
			(at 0 -0.4445 90)
			(size 0.1397 0.1397)
			(layers "F.Cu" "F.Mask" "F.Paste")
			(net "RMII_BMC_MDIO_R")
			(options
				(clearance outline)
				(anchor circle)
			)
			(primitives
				(gr_poly
					(pts
						(arc
							(start -0.1778 -0.2794)
							(mid -0.249642 -0.249642)
							(end -0.2794 -0.1778)
						)
						(arc
							(start -0.2794 0.1778)
							(mid -0.249642 0.249642)
							(end -0.1778 0.2794)
						)
						(arc
							(start 0.1778 0.2794)
							(mid 0.249642 0.249642)
							(end 0.2794 0.1778)
						)
						(arc
							(start 0.2794 -0.1778)
							(mid 0.249642 -0.249642)
							(end 0.1778 -0.2794)
						)
					)
					(width 0)
					(fill yes)
				)
			)
		)
		(pad "2" smd custom
			(at 0 0.4445 90)
			(size 0.1397 0.1397)
			(layers "F.Cu" "F.Mask" "F.Paste")
			(net "RMII_BMC_MDIO")
			(options
				(clearance outline)
				(anchor circle)
			)
			(primitives
				(gr_poly
					(pts
						(arc
							(start -0.1778 -0.2794)
							(mid -0.249642 -0.249642)
							(end -0.2794 -0.1778)
						)
						(arc
							(start -0.2794 0.1778)
							(mid -0.249642 0.249642)
							(end -0.1778 0.2794)
						)
						(arc
							(start 0.1778 0.2794)
							(mid 0.249642 0.249642)
							(end 0.2794 0.1778)
						)
						(arc
							(start 0.2794 -0.1778)
							(mid 0.249642 -0.249642)
							(end 0.1778 -0.2794)
						)
					)
					(width 0)
					(fill yes)
				)
			)
		)
	)
	(footprint ""
		(layer "F.Cu")
		(at 80.91297 -111.76 180)
		(property "Reference" "SC1205"
			(at 0 0 180)
			(layer "F.SilkS")
			(hide yes)
			(effects
				(font
					(size 1.27 1.27)
				)
			)
		)
		(property "Value" "SC10U6D3V5KX-4GP"
			(at -0.0762 -6.1214 180)
			(unlocked yes)
			(layer "F.Fab")
			(hide yes)
			(effects
				(font
					(size 1.016 1.016)
					(thickness 0.1524)
				)
			)
		)
		(property "Device Type" "C805H58"
			(at -0.0762 -8.1534 180)
			(unlocked yes)
			(layer "F.Fab")
			(hide yes)
			(effects
				(font
					(size 1.016 1.016)
					(thickness 0.1524)
				)
			)
		)
		(duplicate_pad_numbers_are_jumpers no)
		(fp_line
			(start 0.635 0)
			(end -0.635 0)
			(stroke
				(width 0.508)
				(type default)
			)
			(layer "F.SilkS")
		)
		(fp_rect
			(start -0.9652 1.778)
			(end 0.9652 -1.778)
			(stroke
				(width 0)
				(type default)
			)
			(fill no)
			(layer "F.CrtYd")
		)
		(fp_poly
			(pts
				(xy -0.9652 -1.778) (xy 0.9652 -1.778) (xy 0.9652 1.778) (xy -0.9652 1.778)
			)
			(stroke
				(width 0)
				(type default)
			)
			(fill no)
			(layer "F.Fab")
		)
		(pad "1" smd rect
			(at 0 -0.9652 180)
			(size 1.397 1.143)
			(layers "F.Cu" "F.Mask" "F.Paste")
			(net "P1V8_E")
		)
		(pad "2" smd rect
			(at 0 0.9652 180)
			(size 1.397 1.143)
			(layers "F.Cu" "F.Mask" "F.Paste")
			(net "GND")
		)
	)
	(footprint ""
		(layer "F.Cu")
		(at 212.598 -217.932 -90)
		(property "Reference" "R685"
			(at 0 0 270)
			(layer "F.SilkS")
			(hide yes)
			(effects
				(font
					(size 1.27 1.27)
				)
			)
		)
		(property "Value" "0R2J-2-GP"
			(at 0.064008 -3.993896 270)
			(unlocked yes)
			(layer "F.Fab")
			(hide yes)
			(effects
				(font
					(size 1.016 1.016)
					(thickness 0.1524)
				)
			)
		)
		(property "Device Type" "R402H16"
			(at 0.064008 -5.517896 270)
			(unlocked yes)
			(layer "F.Fab")
			(hide yes)
			(effects
				(font
					(size 1.016 1.016)
					(thickness 0.1524)
				)
			)
		)
		(duplicate_pad_numbers_are_jumpers no)
		(fp_line
			(start -0.508 -0.9398)
			(end -0.508 0.9398)
			(stroke
				(width 0.1524)
				(type default)
			)
			(layer "F.SilkS")
		)
		(fp_line
			(start 0.508 -0.9398)
			(end -0.508 -0.9398)
			(stroke
				(width 0.1524)
				(type default)
			)
			(layer "F.SilkS")
		)
		(fp_rect
			(start -0.508 0.9398)
			(end 0.508 -0.9398)
			(stroke
				(width 0)
				(type default)
			)
			(fill no)
			(layer "F.CrtYd")
		)
		(fp_rect
			(start -0.508 0.9398)
			(end 0.508 -0.9398)
			(stroke
				(width 0)
				(type default)
			)
			(fill no)
			(layer "F.Fab")
		)
		(pad "1" smd custom
			(at 0 -0.4445 270)
			(size 0.1397 0.1397)
			(layers "F.Cu" "F.Mask" "F.Paste")
			(net "CPU_RESET_N")
			(options
				(clearance outline)
				(anchor circle)
			)
			(primitives
				(gr_poly
					(pts
						(arc
							(start -0.1778 -0.2794)
							(mid -0.249642 -0.249642)
							(end -0.2794 -0.1778)
						)
						(arc
							(start -0.2794 0.1778)
							(mid -0.249642 0.249642)
							(end -0.1778 0.2794)
						)
						(arc
							(start 0.1778 0.2794)
							(mid 0.249642 0.249642)
							(end 0.2794 0.1778)
						)
						(arc
							(start 0.2794 -0.1778)
							(mid 0.249642 -0.249642)
							(end 0.1778 -0.2794)
						)
					)
					(width 0)
					(fill yes)
				)
			)
		)
		(pad "2" smd custom
			(at 0 0.4445 270)
			(size 0.1397 0.1397)
			(layers "F.Cu" "F.Mask" "F.Paste")
			(net "DP_BMC_CPU_RST_N_U177_OUT")
			(options
				(clearance outline)
				(anchor circle)
			)
			(primitives
				(gr_poly
					(pts
						(arc
							(start -0.1778 -0.2794)
							(mid -0.249642 -0.249642)
							(end -0.2794 -0.1778)
						)
						(arc
							(start -0.2794 0.1778)
							(mid -0.249642 0.249642)
							(end -0.1778 0.2794)
						)
						(arc
							(start 0.1778 0.2794)
							(mid 0.249642 0.249642)
							(end 0.2794 0.1778)
						)
						(arc
							(start 0.2794 -0.1778)
							(mid 0.249642 -0.249642)
							(end 0.1778 -0.2794)
						)
					)
					(width 0)
					(fill yes)
				)
			)
		)
	)
	(footprint ""
		(layer "F.Cu")
		(at 60.56757 -144.1704)
		(property "Reference" "SC1285"
			(at 0 0 0)
			(layer "F.SilkS")
			(hide yes)
			(effects
				(font
					(size 1.27 1.27)
				)
			)
		)
		(property "Value" "SCD1U16V2KX-3GP"
			(at 1.1811 -2.7051 0)
			(unlocked yes)
			(layer "F.Fab")
			(hide yes)
			(effects
				(font
					(size 1.016 1.016)
					(thickness 0.1524)
				)
			)
		)
		(property "Device Type" "C402H22"
			(at 1.1811 -4.2291 0)
			(unlocked yes)
			(layer "F.Fab")
			(hide yes)
			(effects
				(font
					(size 1.016 1.016)
					(thickness 0.1524)
				)
			)
		)
		(duplicate_pad_numbers_are_jumpers no)
		(fp_rect
			(start -0.4318 0.9525)
			(end 0.4318 -0.9525)
			(stroke
				(width 0)
				(type default)
			)
			(fill no)
			(layer "F.CrtYd")
		)
		(fp_rect
			(start -0.4318 0.9525)
			(end 0.4318 -0.9525)
			(stroke
				(width 0)
				(type default)
			)
			(fill no)
			(layer "F.Fab")
		)
		(pad "1" smd custom
			(at 0 -0.4445)
			(size 0.1524 0.1524)
			(layers "F.Cu" "F.Mask" "F.Paste")
			(net "P1V8_E")
			(options
				(clearance outline)
				(anchor circle)
			)
			(primitives
				(gr_poly
					(pts
						(arc
							(start 0.3048 -0.2032)
							(mid 0.275042 -0.275042)
							(end 0.2032 -0.3048)
						)
						(arc
							(start -0.2032 -0.3048)
							(mid -0.275042 -0.275042)
							(end -0.3048 -0.2032)
						)
						(arc
							(start -0.3048 0.2032)
							(mid -0.275042 0.275042)
							(end -0.2032 0.3048)
						)
						(arc
							(start 0.2032 0.3048)
							(mid 0.275042 0.275042)
							(end 0.3048 0.2032)
						)
					)
					(width 0)
					(fill yes)
				)
			)
		)
		(pad "2" smd custom
			(at 0 0.4445)
			(size 0.1524 0.1524)
			(layers "F.Cu" "F.Mask" "F.Paste")
			(net "GND")
			(options
				(clearance outline)
				(anchor circle)
			)
			(primitives
				(gr_poly
					(pts
						(arc
							(start 0.3048 -0.2032)
							(mid 0.275042 -0.275042)
							(end 0.2032 -0.3048)
						)
						(arc
							(start -0.2032 -0.3048)
							(mid -0.275042 -0.275042)
							(end -0.3048 -0.2032)
						)
						(arc
							(start -0.3048 0.2032)
							(mid -0.275042 0.275042)
							(end -0.2032 0.3048)
						)
						(arc
							(start 0.2032 0.3048)
							(mid 0.275042 0.275042)
							(end 0.3048 0.2032)
						)
					)
					(width 0)
					(fill yes)
				)
			)
		)
	)
	(footprint ""
		(layer "F.Cu")
		(at 191.135 -122.682 90)
		(property "Reference" "Q77"
			(at 0 0 90)
			(layer "F.SilkS")
			(hide yes)
			(effects
				(font
					(size 1.27 1.27)
				)
			)
		)
		(property "Value" "MMBT3904TT1G-GP"
			(at 0 -9.7282 90)
			(unlocked yes)
			(layer "F.Fab")
			(hide yes)
			(effects
				(font
					(size 1.016 1.016)
					(thickness 0.1524)
				)
			)
		)
		(property "Device Type" "SC75CBE1D6H36"
			(at 0 -11.6332 90)
			(unlocked yes)
			(layer "F.Fab")
			(hide yes)
			(effects
				(font
					(size 1.016 1.016)
					(thickness 0.1524)
				)
			)
		)
		(duplicate_pad_numbers_are_jumpers no)
		(fp_line
			(start 0.9652 -1.3716)
			(end -0.9652 -1.3716)
			(stroke
				(width 0.1524)
				(type default)
			)
			(layer "F.SilkS")
		)
		(fp_line
			(start -0.9652 -1.3716)
			(end -0.9652 1.3716)
			(stroke
				(width 0.1524)
				(type default)
			)
			(layer "F.SilkS")
		)
		(fp_line
			(start 0.9652 1.3716)
			(end 0.9652 -1.3716)
			(stroke
				(width 0.1524)
				(type default)
			)
			(layer "F.SilkS")
		)
		(fp_line
			(start -0.9652 1.3716)
			(end 0.9652 1.3716)
			(stroke
				(width 0.1524)
				(type default)
			)
			(layer "F.SilkS")
		)
		(fp_rect
			(start -1.0414 1.4478)
			(end 1.0414 -1.4478)
			(stroke
				(width 0)
				(type default)
			)
			(fill no)
			(layer "F.CrtYd")
		)
		(fp_poly
			(pts
				(xy -1.0414 -1.4478) (xy 1.0414 -1.4478) (xy 1.0414 1.4478) (xy -1.0414 1.4478)
			)
			(stroke
				(width 0)
				(type default)
			)
			(fill no)
			(layer "F.Fab")
		)
		(pad "B" smd custom
			(at -0.508 0.7112 90)
			(size 0.127 0.127)
			(layers "F.Cu" "F.Mask" "F.Paste")
			(net "P1V8_E_B")
			(options
				(clearance outline)
				(anchor circle)
			)
			(primitives
				(gr_poly
					(pts
						(arc
							(start -0.044958 0.4572)
							(mid -0.192463 0.399794)
							(end -0.254 0.254)
						)
						(xy -0.254 -0.254)
						(arc
							(start -0.253746 -0.254)
							(mid -0.192968 -0.398936)
							(end -0.04699 -0.4572)
						)
						(arc
							(start 0.04699 -0.4572)
							(mid 0.192989 -0.398958)
							(end 0.253746 -0.254)
						)
						(xy 0.254 -0.254)
						(arc
							(start 0.254 0.254)
							(mid 0.192404 0.399734)
							(end 0.044958 0.4572)
						)
					)
					(width 0)
					(fill yes)
				)
			)
		)
		(pad "C" smd custom
			(at 0 -0.7112 90)
			(size 0.127 0.127)
			(layers "F.Cu" "F.Mask" "F.Paste")
			(net "P3V3_STBY_R2")
			(options
				(clearance outline)
				(anchor circle)
			)
			(primitives
				(gr_poly
					(pts
						(arc
							(start -0.044958 0.4572)
							(mid -0.192463 0.399794)
							(end -0.254 0.254)
						)
						(xy -0.254 -0.254)
						(arc
							(start -0.253746 -0.254)
							(mid -0.192968 -0.398936)
							(end -0.04699 -0.4572)
						)
						(arc
							(start 0.04699 -0.4572)
							(mid 0.192989 -0.398958)
							(end 0.253746 -0.254)
						)
						(xy 0.254 -0.254)
						(arc
							(start 0.254 0.254)
							(mid 0.192404 0.399734)
							(end 0.044958 0.4572)
						)
					)
					(width 0)
					(fill yes)
				)
			)
		)
		(pad "E" smd custom
			(at 0.508 0.7112 90)
			(size 0.127 0.127)
			(layers "F.Cu" "F.Mask" "F.Paste")
			(net "GND")
			(options
				(clearance outline)
				(anchor circle)
			)
			(primitives
				(gr_poly
					(pts
						(arc
							(start -0.044958 0.4572)
							(mid -0.192463 0.399794)
							(end -0.254 0.254)
						)
						(xy -0.254 -0.254)
						(arc
							(start -0.253746 -0.254)
							(mid -0.192968 -0.398936)
							(end -0.04699 -0.4572)
						)
						(arc
							(start 0.04699 -0.4572)
							(mid 0.192989 -0.398958)
							(end 0.253746 -0.254)
						)
						(xy 0.254 -0.254)
						(arc
							(start 0.254 0.254)
							(mid 0.192404 0.399734)
							(end 0.044958 0.4572)
						)
					)
					(width 0)
					(fill yes)
				)
			)
		)
	)
)
